# T6G (Grand Teton) — schematic netlist excerpt (pin names and nets, part order shuffled) for the footprints in the layout excerpt that follows; sources: Cadence DE-HDL packaged netlist, KiCad conversion of 04192023_DAF0TMB3IC0_F0TG_MB_C_brd_V02_OCP.brd

C2223  Q_CAP  22UF 4V 20% X6S  pkg C0402  page 69 : A = PVDDCR_CPU1_P0 ; B = GND
R83  Q_RES  100K 1% CHIP  pkg 0402LF  page 132 : A = RMII_BMC_OCP_TXD_0 ; B = GND

(kicad_pcb
	(version 20260206)
	(generator "pcbnew")
	(generator_version "10.0")
	(general
		(thickness 1.6)
		(legacy_teardrops no)
	)
	(paper "A4")
	(title_block
		(title "04192023_DAF0TMB3IC0_F0TG_MB_C_brd_V02_OCP.brd")
		(comment 1 "Grand Teton / footprints 7118-7119 of 8354")
	)
	(layers
		(0 "F.Cu" signal "TOP")
		(4 "In1.Cu" signal "GND")
		(6 "In2.Cu" signal "IN1")
		(8 "In3.Cu" signal "GND1")
		(10 "In4.Cu" signal "IN2")
		(12 "In5.Cu" signal "GND2")
		(14 "In6.Cu" signal "IN3")
		(16 "In7.Cu" signal "GND3")
		(18 "In8.Cu" signal "VCC")
		(20 "In9.Cu" signal "VCC1")
		(22 "In10.Cu" signal "GND4")
		(24 "In11.Cu" signal "IN4")
		(26 "In12.Cu" signal "GND5")
		(28 "In13.Cu" signal "IN5")
		(30 "In14.Cu" signal "GND6")
		(32 "In15.Cu" signal "IN6")
		(34 "In16.Cu" signal "GND7")
		(2 "B.Cu" signal "BOTTOM")
		(9 "F.Adhes" user "F.Adhesive")
		(11 "B.Adhes" user "B.Adhesive")
		(13 "F.Paste" user "Package Geometry/Pastemask Top")
		(15 "B.Paste" user "Package Geometry/Pastemask Bottom")
		(5 "F.SilkS" user "Ref Des/Silkscreen Top")
		(7 "B.SilkS" user "Ref Des/Silkscreen Bottom")
		(1 "F.Mask" user "Board Geometry/Soldermask Top")
		(3 "B.Mask" user "Board Geometry/Soldermask Bottom")
		(17 "Dwgs.User" user "User.Drawings")
		(19 "Cmts.User" user "User.Comments")
		(21 "Eco1.User" user "User.Eco1")
		(23 "Eco2.User" user "User.Eco2")
		(25 "Edge.Cuts" user "Board Geometry/Outline")
		(27 "Margin" user)
		(31 "F.CrtYd" user "Package Geometry/Place Bound Top")
		(29 "B.CrtYd" user "Package Geometry/Place Bound Bottom")
		(35 "F.Fab" user "Ref Des/Assembly Top")
		(33 "B.Fab" user "Ref Des/Assembly Bottom")
	)
	(footprint ""
		(layer "B.Cu")
		(at 218.066112 -67.661028 90)
		(property "Reference" "R83"
			(at 0 0 90)
			(layer "B.SilkS")
			(hide yes)
			(effects
				(font
					(size 1.27 1.27)
				)
				(justify mirror)
			)
		)
		(property "Value" ""
			(at 0 0 90)
			(layer "B.Fab")
			(effects
				(font
					(size 1.27 1.27)
				)
				(justify mirror)
			)
		)
		(duplicate_pad_numbers_are_jumpers no)
		(fp_line
			(start 0.7874 -0.4064)
			(end -0.7874 -0.4064)
			(stroke
				(width 0.1524)
				(type default)
			)
			(layer "B.SilkS")
		)
		(fp_line
			(start -0.7874 -0.4064)
			(end -0.7874 0.4064)
			(stroke
				(width 0.1524)
				(type default)
			)
			(layer "B.SilkS")
		)
		(fp_line
			(start 0.7874 0.4064)
			(end 0.7874 -0.4064)
			(stroke
				(width 0.1524)
				(type default)
			)
			(layer "B.SilkS")
		)
		(fp_line
			(start -0.7874 0.4064)
			(end 0.7874 0.4064)
			(stroke
				(width 0.1524)
				(type default)
			)
			(layer "B.SilkS")
		)
		(fp_line
			(start 0.67945 -0.305054)
			(end 0.12065 -0.305054)
			(stroke
				(width 0.1)
				(type default)
			)
			(layer "B.Fab")
		)
		(fp_line
			(start 0.12065 -0.305054)
			(end 0.12065 -0.2794)
			(stroke
				(width 0.1)
				(type default)
			)
			(layer "B.Fab")
		)
		(fp_line
			(start -0.12065 -0.3048)
			(end -0.67945 -0.3048)
			(stroke
				(width 0.1)
				(type default)
			)
			(layer "B.Fab")
		)
		(fp_line
			(start -0.67945 -0.3048)
			(end -0.67945 0.3048)
			(stroke
				(width 0.1)
				(type default)
			)
			(layer "B.Fab")
		)
		(fp_line
			(start 0.12065 -0.2794)
			(end -0.12065 -0.2794)
			(stroke
				(width 0.1)
				(type default)
			)
			(layer "B.Fab")
		)
		(fp_line
			(start -0.12065 -0.2794)
			(end -0.12065 -0.3048)
			(stroke
				(width 0.1)
				(type default)
			)
			(layer "B.Fab")
		)
		(fp_line
			(start 0.12065 0.2794)
			(end 0.12065 0.3048)
			(stroke
				(width 0.1)
				(type default)
			)
			(layer "B.Fab")
		)
		(fp_line
			(start -0.120396 0.2794)
			(end 0.12065 0.2794)
			(stroke
				(width 0.1)
				(type default)
			)
			(layer "B.Fab")
		)
		(fp_line
			(start 0.67945 0.3048)
			(end 0.67945 -0.305054)
			(stroke
				(width 0.1)
				(type default)
			)
			(layer "B.Fab")
		)
		(fp_line
			(start 0.12065 0.3048)
			(end 0.67945 0.3048)
			(stroke
				(width 0.1)
				(type default)
			)
			(layer "B.Fab")
		)
		(fp_line
			(start -0.120396 0.3048)
			(end -0.120396 0.2794)
			(stroke
				(width 0.1)
				(type default)
			)
			(layer "B.Fab")
		)
		(fp_line
			(start -0.67945 0.3048)
			(end -0.120396 0.3048)
			(stroke
				(width 0.1)
				(type default)
			)
			(layer "B.Fab")
		)
		(pad "1" smd circle
			(at 0.40005 0 270)
			(size 0 0)
			(layers "B.Cu" "B.Mask" "B.Paste")
			(net "RMII_BMC_OCP_TXD_0")
		)
		(pad "2" smd circle
			(at -0.40005 0 270)
			(size 0 0)
			(layers "B.Cu" "B.Mask" "B.Paste")
			(net "GND")
		)
	)
	(footprint ""
		(layer "B.Cu")
		(at 373.202454 -267.498576)
		(property "Reference" "C2223"
			(at 0 0 0)
			(layer "B.SilkS")
			(hide yes)
			(effects
				(font
					(size 1.27 1.27)
				)
				(justify mirror)
			)
		)
		(property "Value" ""
			(at 0 0 0)
			(layer "B.Fab")
			(effects
				(font
					(size 1.27 1.27)
				)
				(justify mirror)
			)
		)
		(duplicate_pad_numbers_are_jumpers no)
		(fp_line
			(start -0.7874 -0.4064)
			(end -0.7874 0.4064)
			(stroke
				(width 0.1524)
				(type default)
			)
			(layer "B.SilkS")
		)
		(fp_line
			(start -0.7874 0.4064)
			(end 0.7874 0.4064)
			(stroke
				(width 0.1524)
				(type default)
			)
			(layer "B.SilkS")
		)
		(fp_line
			(start 0.7874 -0.4064)
			(end -0.7874 -0.4064)
			(stroke
				(width 0.1524)
				(type default)
			)
			(layer "B.SilkS")
		)
		(fp_line
			(start 0.7874 0.4064)
			(end 0.7874 -0.4064)
			(stroke
				(width 0.1524)
				(type default)
			)
			(layer "B.SilkS")
		)
		(fp_line
			(start -0.67945 -0.3048)
			(end -0.67945 0.3048)
			(stroke
				(width 0.1)
				(type default)
			)
			(layer "B.Fab")
		)
		(fp_line
			(start -0.67945 0.3048)
			(end -0.120396 0.3048)
			(stroke
				(width 0.1)
				(type default)
			)
			(layer "B.Fab")
		)
		(fp_line
			(start -0.12065 -0.3048)
			(end -0.67945 -0.3048)
			(stroke
				(width 0.1)
				(type default)
			)
			(layer "B.Fab")
		)
		(fp_line
			(start -0.12065 -0.2794)
			(end -0.12065 -0.3048)
			(stroke
				(width 0.1)
				(type default)
			)
			(layer "B.Fab")
		)
		(fp_line
			(start -0.120396 0.2794)
			(end 0.12065 0.2794)
			(stroke
				(width 0.1)
				(type default)
			)
			(layer "B.Fab")
		)
		(fp_line
			(start -0.120396 0.3048)
			(end -0.120396 0.2794)
			(stroke
				(width 0.1)
				(type default)
			)
			(layer "B.Fab")
		)
		(fp_line
			(start 0.12065 -0.305054)
			(end 0.12065 -0.2794)
			(stroke
				(width 0.1)
				(type default)
			)
			(layer "B.Fab")
		)
		(fp_line
			(start 0.12065 -0.2794)
			(end -0.12065 -0.2794)
			(stroke
				(width 0.1)
				(type default)
			)
			(layer "B.Fab")
		)
		(fp_line
			(start 0.12065 0.2794)
			(end 0.12065 0.3048)
			(stroke
				(width 0.1)
				(type default)
			)
			(layer "B.Fab")
		)
		(fp_line
			(start 0.12065 0.3048)
			(end 0.67945 0.3048)
			(stroke
				(width 0.1)
				(type default)
			)
			(layer "B.Fab")
		)
		(fp_line
			(start 0.67945 -0.305054)
			(end 0.12065 -0.305054)
			(stroke
				(width 0.1)
				(type default)
			)
			(layer "B.Fab")
		)
		(fp_line
			(start 0.67945 0.3048)
			(end 0.67945 -0.305054)
			(stroke
				(width 0.1)
				(type default)
			)
			(layer "B.Fab")
		)
		(pad "1" smd circle
			(at 0.40005 0 180)
			(size 0 0)
			(layers "B.Cu" "B.Mask" "B.Paste")
			(net "PVDDCR_CPU1_P0")
		)
		(pad "2" smd circle
			(at -0.40005 0 180)
			(size 0 0)
			(layers "B.Cu" "B.Mask" "B.Paste")
			(net "GND")
		)
	)
)
